# S9S_MB_2U (Grand Teton) — schematic netlist excerpt (pin names and nets, part order shuffled) for the footprints in the layout excerpt that follows; sources: Cadence DE-HDL packaged netlist, KiCad conversion of 03242023_DA0F0TMBIJ0_F0T_Motherboard_J_brd_V01_OCP.brd

C1538  Q_CAP_DIFFBUS  DIFF BUS_0.22UF 6.3V 20% X6S  pkg C0201  page 177 : \1\ = P5E_CPU1_PE3_TX_C_DN<4> ; \2\ = P5E_CPU1_PE3_TX_DN<4>
R124  Q_RES  0 5% CHIP  pkg 0402LF  page 125 : A = PWRGD_DRAMPWRGD_CPU1_CD_R_LVC1 ; B = PWRGD_DRAMPWRGD_CPU1_CD_LVC1_R2
C753  Q_CAP_DIFFBUS  DIFF BUS_0.22UF 6.3V 20% X6S  pkg C0201  page 176 : \1\ = P5E_CPU1_PE2_TX_C_DP<10> ; \2\ = P5E_CPU1_PE2_TX_DP<10>
PC1238  Q_CAP  22UF 4V 20% X6S  pkg C0805  page 263 : A = P1V8_PCH_AUX ; B = GND

(kicad_pcb
	(version 20260206)
	(generator "pcbnew")
	(generator_version "10.0")
	(general
		(thickness 1.6)
		(legacy_teardrops no)
	)
	(paper "A4")
	(title_block
		(title "03242023_DA0F0TMBIJ0_F0T_Motherboard_J_brd_V01_OCP.brd")
		(comment 1 "Grand Teton / footprints 2644-2647 of 6105")
	)
	(layers
		(0 "F.Cu" signal "TOP")
		(4 "In1.Cu" signal "GND")
		(6 "In2.Cu" signal "IN1")
		(8 "In3.Cu" signal "GND1")
		(10 "In4.Cu" signal "IN2")
		(12 "In5.Cu" signal "GND2")
		(14 "In6.Cu" signal "IN3")
		(16 "In7.Cu" signal "GND3")
		(18 "In8.Cu" signal "VCC")
		(20 "In9.Cu" signal "VCC1")
		(22 "In10.Cu" signal "GND4")
		(24 "In11.Cu" signal "IN4")
		(26 "In12.Cu" signal "GND5")
		(28 "In13.Cu" signal "IN5")
		(30 "In14.Cu" signal "GND6")
		(32 "In15.Cu" signal "IN6")
		(34 "In16.Cu" signal "GND7")
		(2 "B.Cu" signal "BOTTOM")
		(9 "F.Adhes" user "F.Adhesive")
		(11 "B.Adhes" user "B.Adhesive")
		(13 "F.Paste" user "Package Geometry/Pastemask Top")
		(15 "B.Paste" user "Package Geometry/Pastemask Bottom")
		(5 "F.SilkS" user "Ref Des/Silkscreen Top")
		(7 "B.SilkS" user "Ref Des/Silkscreen Bottom")
		(1 "F.Mask" user "Board Geometry/Soldermask Top")
		(3 "B.Mask" user "Board Geometry/Soldermask Bottom")
		(17 "Dwgs.User" user "User.Drawings")
		(19 "Cmts.User" user "User.Comments")
		(21 "Eco1.User" user "User.Eco1")
		(23 "Eco2.User" user "User.Eco2")
		(25 "Edge.Cuts" user "Board Geometry/Outline")
		(27 "Margin" user)
		(31 "F.CrtYd" user "Package Geometry/Place Bound Top")
		(29 "B.CrtYd" user "Package Geometry/Place Bound Bottom")
		(35 "F.Fab" user "Ref Des/Assembly Top")
		(33 "B.Fab" user "Ref Des/Assembly Bottom")
	)
	(footprint ""
		(layer "F.Cu")
		(at 135.445754 -402.371052 -90)
		(property "Reference" "C753"
			(at 0 0 270)
			(layer "F.SilkS")
			(hide yes)
			(effects
				(font
					(size 1.27 1.27)
				)
			)
		)
		(property "Value" ""
			(at 0 0 270)
			(layer "F.Fab")
			(effects
				(font
					(size 1.27 1.27)
				)
			)
		)
		(duplicate_pad_numbers_are_jumpers no)
		(fp_line
			(start -0.299974 0.150114)
			(end -0.299974 -0.150114)
			(stroke
				(width 0.1)
				(type default)
			)
			(layer "F.Fab")
		)
		(fp_line
			(start 0.299974 0.150114)
			(end -0.299974 0.150114)
			(stroke
				(width 0.1)
				(type default)
			)
			(layer "F.Fab")
		)
		(fp_line
			(start -0.299974 -0.150114)
			(end 0.299974 -0.150114)
			(stroke
				(width 0.1)
				(type default)
			)
			(layer "F.Fab")
		)
		(fp_line
			(start 0.299974 -0.150114)
			(end 0.299974 0.150114)
			(stroke
				(width 0.1)
				(type default)
			)
			(layer "F.Fab")
		)
		(pad "1" smd rect
			(at -0.2667 0 270)
			(size 0.3048 0.381)
			(layers "F.Cu" "F.Mask" "F.Paste")
			(net "P5E_CPU1_PE2_TX_C_DP<10>")
		)
		(pad "2" smd rect
			(at 0.2667 0 270)
			(size 0.3048 0.381)
			(layers "F.Cu" "F.Mask" "F.Paste")
			(net "P5E_CPU1_PE2_TX_DP<10>")
		)
	)
	(footprint ""
		(layer "F.Cu")
		(at 155.171394 -408.517344 -90)
		(property "Reference" "C1538"
			(at 0 0 270)
			(layer "F.SilkS")
			(hide yes)
			(effects
				(font
					(size 1.27 1.27)
				)
			)
		)
		(property "Value" ""
			(at 0 0 270)
			(layer "F.Fab")
			(effects
				(font
					(size 1.27 1.27)
				)
			)
		)
		(duplicate_pad_numbers_are_jumpers no)
		(fp_line
			(start -0.299974 0.150114)
			(end -0.299974 -0.150114)
			(stroke
				(width 0.1)
				(type default)
			)
			(layer "F.Fab")
		)
		(fp_line
			(start 0.299974 0.150114)
			(end -0.299974 0.150114)
			(stroke
				(width 0.1)
				(type default)
			)
			(layer "F.Fab")
		)
		(fp_line
			(start -0.299974 -0.150114)
			(end 0.299974 -0.150114)
			(stroke
				(width 0.1)
				(type default)
			)
			(layer "F.Fab")
		)
		(fp_line
			(start 0.299974 -0.150114)
			(end 0.299974 0.150114)
			(stroke
				(width 0.1)
				(type default)
			)
			(layer "F.Fab")
		)
		(pad "1" smd rect
			(at -0.2667 0 270)
			(size 0.3048 0.381)
			(layers "F.Cu" "F.Mask" "F.Paste")
			(net "P5E_CPU1_PE3_TX_C_DN<4>")
		)
		(pad "2" smd rect
			(at 0.2667 0 270)
			(size 0.3048 0.381)
			(layers "F.Cu" "F.Mask" "F.Paste")
			(net "P5E_CPU1_PE3_TX_DN<4>")
		)
	)
	(footprint ""
		(layer "F.Cu")
		(at 174.87138 -99.863148 -90)
		(property "Reference" "R124"
			(at 0 0 270)
			(layer "F.SilkS")
			(hide yes)
			(effects
				(font
					(size 1.27 1.27)
				)
			)
		)
		(property "Value" ""
			(at 0 0 270)
			(layer "F.Fab")
			(effects
				(font
					(size 1.27 1.27)
				)
			)
		)
		(duplicate_pad_numbers_are_jumpers no)
		(fp_line
			(start -0.7874 0.4064)
			(end -0.7874 -0.4064)
			(stroke
				(width 0.1524)
				(type default)
			)
			(layer "F.SilkS")
		)
		(fp_line
			(start 0.7874 0.4064)
			(end -0.7874 0.4064)
			(stroke
				(width 0.1524)
				(type default)
			)
			(layer "F.SilkS")
		)
		(fp_line
			(start -0.7874 -0.4064)
			(end 0.7874 -0.4064)
			(stroke
				(width 0.1524)
				(type default)
			)
			(layer "F.SilkS")
		)
		(fp_line
			(start 0.7874 -0.4064)
			(end 0.7874 0.4064)
			(stroke
				(width 0.1524)
				(type default)
			)
			(layer "F.SilkS")
		)
		(fp_line
			(start -0.67945 0.3048)
			(end -0.67945 -0.305054)
			(stroke
				(width 0.1)
				(type default)
			)
			(layer "F.Fab")
		)
		(fp_line
			(start -0.12065 0.3048)
			(end -0.67945 0.3048)
			(stroke
				(width 0.1)
				(type default)
			)
			(layer "F.Fab")
		)
		(fp_line
			(start 0.120396 0.3048)
			(end 0.120396 0.2794)
			(stroke
				(width 0.1)
				(type default)
			)
			(layer "F.Fab")
		)
		(fp_line
			(start 0.67945 0.3048)
			(end 0.120396 0.3048)
			(stroke
				(width 0.1)
				(type default)
			)
			(layer "F.Fab")
		)
		(fp_line
			(start -0.12065 0.2794)
			(end -0.12065 0.3048)
			(stroke
				(width 0.1)
				(type default)
			)
			(layer "F.Fab")
		)
		(fp_line
			(start 0.120396 0.2794)
			(end -0.12065 0.2794)
			(stroke
				(width 0.1)
				(type default)
			)
			(layer "F.Fab")
		)
		(fp_line
			(start -0.12065 -0.2794)
			(end 0.12065 -0.2794)
			(stroke
				(width 0.1)
				(type default)
			)
			(layer "F.Fab")
		)
		(fp_line
			(start 0.12065 -0.2794)
			(end 0.12065 -0.3048)
			(stroke
				(width 0.1)
				(type default)
			)
			(layer "F.Fab")
		)
		(fp_line
			(start 0.12065 -0.3048)
			(end 0.67945 -0.3048)
			(stroke
				(width 0.1)
				(type default)
			)
			(layer "F.Fab")
		)
		(fp_line
			(start 0.67945 -0.3048)
			(end 0.67945 0.3048)
			(stroke
				(width 0.1)
				(type default)
			)
			(layer "F.Fab")
		)
		(fp_line
			(start -0.67945 -0.305054)
			(end -0.12065 -0.305054)
			(stroke
				(width 0.1)
				(type default)
			)
			(layer "F.Fab")
		)
		(fp_line
			(start -0.12065 -0.305054)
			(end -0.12065 -0.2794)
			(stroke
				(width 0.1)
				(type default)
			)
			(layer "F.Fab")
		)
		(pad "1" smd circle
			(at -0.40005 0 270)
			(size 0 0)
			(layers "F.Cu" "F.Mask" "F.Paste")
			(net "PWRGD_DRAMPWRGD_CPU1_CD_R_LVC1")
		)
		(pad "2" smd circle
			(at 0.40005 0 270)
			(size 0 0)
			(layers "F.Cu" "F.Mask" "F.Paste")
			(net "PWRGD_DRAMPWRGD_CPU1_CD_LVC1_R2")
		)
	)
	(footprint ""
		(layer "F.Cu")
		(at 376.468132 -80.354424)
		(property "Reference" "PC1238"
			(at 0 0 0)
			(layer "F.SilkS")
			(hide yes)
			(effects
				(font
					(size 1.27 1.27)
				)
			)
		)
		(property "Value" ""
			(at 0 0 0)
			(layer "F.Fab")
			(effects
				(font
					(size 1.27 1.27)
				)
			)
		)
		(duplicate_pad_numbers_are_jumpers no)
		(fp_line
			(start -1.524 -0.762)
			(end 1.524 -0.762)
			(stroke
				(width 0.1524)
				(type default)
			)
			(layer "F.SilkS")
		)
		(fp_line
			(start -1.524 0.762)
			(end -1.524 -0.762)
			(stroke
				(width 0.1524)
				(type default)
			)
			(layer "F.SilkS")
		)
		(fp_line
			(start 1.524 -0.762)
			(end 1.524 0.762)
			(stroke
				(width 0.1524)
				(type default)
			)
			(layer "F.SilkS")
		)
		(fp_line
			(start 1.524 0.762)
			(end -1.524 0.762)
			(stroke
				(width 0.1524)
				(type default)
			)
			(layer "F.SilkS")
		)
		(fp_line
			(start -1.1049 -0.724916)
			(end -1.1049 0.724916)
			(stroke
				(width 0.1)
				(type default)
			)
			(layer "F.Fab")
		)
		(fp_line
			(start -1.1049 0.724916)
			(end 1.1049 0.724916)
			(stroke
				(width 0.1)
				(type default)
			)
			(layer "F.Fab")
		)
		(fp_line
			(start 1.1049 -0.724916)
			(end -1.1049 -0.724916)
			(stroke
				(width 0.1)
				(type default)
			)
			(layer "F.Fab")
		)
		(fp_line
			(start 1.1049 0.724916)
			(end 1.1049 -0.724916)
			(stroke
				(width 0.1)
				(type default)
			)
			(layer "F.Fab")
		)
		(pad "1" smd rect
			(at -0.889 0 180)
			(size 1.016 1.27)
			(layers "F.Cu" "F.Mask" "F.Paste")
			(net "P1V8_PCH_AUX")
		)
		(pad "2" smd rect
			(at 0.889 0 180)
			(size 1.016 1.27)
			(layers "F.Cu" "F.Mask" "F.Paste")
			(net "GND")
		)
	)
)
